(kicad_pcb
	(version 20260206)
	(generator "pcbnew")
	(generator_version "10.0")
	(general
		(thickness 1.6)
		(legacy_teardrops no)
	)
	(paper "A4")
	(title_block
		(title "04192023_DAF0TMB3IC0_F0TG_MB_C_brd_V02_OCP.brd")
		(comment 1 "Grand Teton / footprints 2957-2963 of 8354")
	)
	(layers
		(0 "F.Cu" signal "TOP")
		(4 "In1.Cu" signal "GND")
		(6 "In2.Cu" signal "IN1")
		(8 "In3.Cu" signal "GND1")
		(10 "In4.Cu" signal "IN2")
		(12 "In5.Cu" signal "GND2")
		(14 "In6.Cu" signal "IN3")
		(16 "In7.Cu" signal "GND3")
		(18 "In8.Cu" signal "VCC")
		(20 "In9.Cu" signal "VCC1")
		(22 "In10.Cu" signal "GND4")
		(24 "In11.Cu" signal "IN4")
		(26 "In12.Cu" signal "GND5")
		(28 "In13.Cu" signal "IN5")
		(30 "In14.Cu" signal "GND6")
		(32 "In15.Cu" signal "IN6")
		(34 "In16.Cu" signal "GND7")
		(2 "B.Cu" signal "BOTTOM")
		(9 "F.Adhes" user "F.Adhesive")
		(11 "B.Adhes" user "B.Adhesive")
		(13 "F.Paste" user "Package Geometry/Pastemask Top")
		(15 "B.Paste" user "Package Geometry/Pastemask Bottom")
		(5 "F.SilkS" user "Ref Des/Silkscreen Top")
		(7 "B.SilkS" user "Ref Des/Silkscreen Bottom")
		(1 "F.Mask" user "Board Geometry/Soldermask Top")
		(3 "B.Mask" user "Board Geometry/Soldermask Bottom")
		(17 "Dwgs.User" user "User.Drawings")
		(19 "Cmts.User" user "User.Comments")
		(21 "Eco1.User" user "User.Eco1")
		(23 "Eco2.User" user "User.Eco2")
		(25 "Edge.Cuts" user "Board Geometry/Outline")
		(27 "Margin" user)
		(31 "F.CrtYd" user "Package Geometry/Place Bound Top")
		(29 "B.CrtYd" user "Package Geometry/Place Bound Bottom")
		(35 "F.Fab" user "Ref Des/Assembly Top")
		(33 "B.Fab" user "Ref Des/Assembly Bottom")
	)
	(footprint ""
		(layer "F.Cu")
		(at 127.705104 -54.17439 180)
		(property "Reference" "C1518"
			(at 0 0 180)
			(layer "F.SilkS")
			(hide yes)
			(effects
				(font
					(size 1.27 1.27)
				)
			)
		)
		(property "Value" ""
			(at 0 0 180)
			(layer "F.Fab")
			(effects
				(font
					(size 1.27 1.27)
				)
			)
		)
		(duplicate_pad_numbers_are_jumpers no)
		(fp_line
			(start 0.7874 0.4064)
			(end -0.7874 0.4064)
			(stroke
				(width 0.1524)
				(type default)
			)
			(layer "F.SilkS")
		)
		(fp_line
			(start 0.7874 -0.4064)
			(end 0.7874 0.4064)
			(stroke
				(width 0.1524)
				(type default)
			)
			(layer "F.SilkS")
		)
		(fp_line
			(start -0.7874 0.4064)
			(end -0.7874 -0.4064)
			(stroke
				(width 0.1524)
				(type default)
			)
			(layer "F.SilkS")
		)
		(fp_line
			(start -0.7874 -0.4064)
			(end 0.7874 -0.4064)
			(stroke
				(width 0.1524)
				(type default)
			)
			(layer "F.SilkS")
		)
		(fp_line
			(start 0.67945 0.3048)
			(end 0.120396 0.3048)
			(stroke
				(width 0.1)
				(type default)
			)
			(layer "F.Fab")
		)
		(fp_line
			(start 0.67945 -0.3048)
			(end 0.67945 0.3048)
			(stroke
				(width 0.1)
				(type default)
			)
			(layer "F.Fab")
		)
		(fp_line
			(start 0.12065 -0.2794)
			(end 0.12065 -0.3048)
			(stroke
				(width 0.1)
				(type default)
			)
			(layer "F.Fab")
		)
		(fp_line
			(start 0.12065 -0.3048)
			(end 0.67945 -0.3048)
			(stroke
				(width 0.1)
				(type default)
			)
			(layer "F.Fab")
		)
		(fp_line
			(start 0.120396 0.3048)
			(end 0.120396 0.2794)
			(stroke
				(width 0.1)
				(type default)
			)
			(layer "F.Fab")
		)
		(fp_line
			(start 0.120396 0.2794)
			(end -0.12065 0.2794)
			(stroke
				(width 0.1)
				(type default)
			)
			(layer "F.Fab")
		)
		(fp_line
			(start -0.12065 0.3048)
			(end -0.67945 0.3048)
			(stroke
				(width 0.1)
				(type default)
			)
			(layer "F.Fab")
		)
		(fp_line
			(start -0.12065 0.2794)
			(end -0.12065 0.3048)
			(stroke
				(width 0.1)
				(type default)
			)
			(layer "F.Fab")
		)
		(fp_line
			(start -0.12065 -0.2794)
			(end 0.12065 -0.2794)
			(stroke
				(width 0.1)
				(type default)
			)
			(layer "F.Fab")
		)
		(fp_line
			(start -0.12065 -0.305054)
			(end -0.12065 -0.2794)
			(stroke
				(width 0.1)
				(type default)
			)
			(layer "F.Fab")
		)
		(fp_line
			(start -0.67945 0.3048)
			(end -0.67945 -0.305054)
			(stroke
				(width 0.1)
				(type default)
			)
			(layer "F.Fab")
		)
		(fp_line
			(start -0.67945 -0.305054)
			(end -0.12065 -0.305054)
			(stroke
				(width 0.1)
				(type default)
			)
			(layer "F.Fab")
		)
		(pad "1" smd circle
			(at -0.40005 0 180)
			(size 0 0)
			(layers "F.Cu" "F.Mask" "F.Paste")
			(net "PVDD18_S5_P0")
		)
		(pad "2" smd circle
			(at 0.40005 0 180)
			(size 0 0)
			(layers "F.Cu" "F.Mask" "F.Paste")
			(net "GND")
		)
	)
	(footprint ""
		(layer "F.Cu")
		(at 358.021128 -394.82268 90)
		(property "Reference" "C590"
			(at 0 0 90)
			(layer "F.SilkS")
			(hide yes)
			(effects
				(font
					(size 1.27 1.27)
				)
			)
		)
		(property "Value" ""
			(at 0 0 90)
			(layer "F.Fab")
			(effects
				(font
					(size 1.27 1.27)
				)
			)
		)
		(duplicate_pad_numbers_are_jumpers no)
		(fp_line
			(start 0.7874 -0.4064)
			(end 0.7874 0.4064)
			(stroke
				(width 0.1524)
				(type default)
			)
			(layer "F.SilkS")
		)
		(fp_line
			(start -0.7874 -0.4064)
			(end 0.7874 -0.4064)
			(stroke
				(width 0.1524)
				(type default)
			)
			(layer "F.SilkS")
		)
		(fp_line
			(start 0.7874 0.4064)
			(end -0.7874 0.4064)
			(stroke
				(width 0.1524)
				(type default)
			)
			(layer "F.SilkS")
		)
		(fp_line
			(start -0.7874 0.4064)
			(end -0.7874 -0.4064)
			(stroke
				(width 0.1524)
				(type default)
			)
			(layer "F.SilkS")
		)
		(fp_line
			(start -0.12065 -0.305054)
			(end -0.12065 -0.2794)
			(stroke
				(width 0.1)
				(type default)
			)
			(layer "F.Fab")
		)
		(fp_line
			(start -0.67945 -0.305054)
			(end -0.12065 -0.305054)
			(stroke
				(width 0.1)
				(type default)
			)
			(layer "F.Fab")
		)
		(fp_line
			(start 0.67945 -0.3048)
			(end 0.67945 0.3048)
			(stroke
				(width 0.1)
				(type default)
			)
			(layer "F.Fab")
		)
		(fp_line
			(start 0.12065 -0.3048)
			(end 0.67945 -0.3048)
			(stroke
				(width 0.1)
				(type default)
			)
			(layer "F.Fab")
		)
		(fp_line
			(start 0.12065 -0.2794)
			(end 0.12065 -0.3048)
			(stroke
				(width 0.1)
				(type default)
			)
			(layer "F.Fab")
		)
		(fp_line
			(start -0.12065 -0.2794)
			(end 0.12065 -0.2794)
			(stroke
				(width 0.1)
				(type default)
			)
			(layer "F.Fab")
		)
		(fp_line
			(start 0.120396 0.2794)
			(end -0.12065 0.2794)
			(stroke
				(width 0.1)
				(type default)
			)
			(layer "F.Fab")
		)
		(fp_line
			(start -0.12065 0.2794)
			(end -0.12065 0.3048)
			(stroke
				(width 0.1)
				(type default)
			)
			(layer "F.Fab")
		)
		(fp_line
			(start 0.67945 0.3048)
			(end 0.120396 0.3048)
			(stroke
				(width 0.1)
				(type default)
			)
			(layer "F.Fab")
		)
		(fp_line
			(start 0.120396 0.3048)
			(end 0.120396 0.2794)
			(stroke
				(width 0.1)
				(type default)
			)
			(layer "F.Fab")
		)
		(fp_line
			(start -0.12065 0.3048)
			(end -0.67945 0.3048)
			(stroke
				(width 0.1)
				(type default)
			)
			(layer "F.Fab")
		)
		(fp_line
			(start -0.67945 0.3048)
			(end -0.67945 -0.305054)
			(stroke
				(width 0.1)
				(type default)
			)
			(layer "F.Fab")
		)
		(pad "1" smd circle
			(at -0.40005 0 90)
			(size 0 0)
			(layers "F.Cu" "F.Mask" "F.Paste")
			(net "P1V8_CPU0_RT1_1A")
		)
		(pad "2" smd circle
			(at 0.40005 0 90)
			(size 0 0)
			(layers "F.Cu" "F.Mask" "F.Paste")
			(net "GND")
		)
	)
	(footprint ""
		(layer "F.Cu")
		(at 215.4301 -405.036782 180)
		(property "Reference" "PC2226"
			(at 0 0 180)
			(layer "F.SilkS")
			(hide yes)
			(effects
				(font
					(size 1.27 1.27)
				)
			)
		)
		(property "Value" ""
			(at 0 0 180)
			(layer "F.Fab")
			(effects
				(font
					(size 1.27 1.27)
				)
			)
		)
		(duplicate_pad_numbers_are_jumpers no)
		(fp_line
			(start 0.7874 0.4064)
			(end -0.7874 0.4064)
			(stroke
				(width 0.1524)
				(type default)
			)
			(layer "F.SilkS")
		)
		(fp_line
			(start 0.7874 -0.4064)
			(end 0.7874 0.4064)
			(stroke
				(width 0.1524)
				(type default)
			)
			(layer "F.SilkS")
		)
		(fp_line
			(start -0.7874 0.4064)
			(end -0.7874 -0.4064)
			(stroke
				(width 0.1524)
				(type default)
			)
			(layer "F.SilkS")
		)
		(fp_line
			(start -0.7874 -0.4064)
			(end 0.7874 -0.4064)
			(stroke
				(width 0.1524)
				(type default)
			)
			(layer "F.SilkS")
		)
		(fp_line
			(start 0.67945 0.3048)
			(end 0.120396 0.3048)
			(stroke
				(width 0.1)
				(type default)
			)
			(layer "F.Fab")
		)
		(fp_line
			(start 0.67945 -0.3048)
			(end 0.67945 0.3048)
			(stroke
				(width 0.1)
				(type default)
			)
			(layer "F.Fab")
		)
		(fp_line
			(start 0.12065 -0.2794)
			(end 0.12065 -0.3048)
			(stroke
				(width 0.1)
				(type default)
			)
			(layer "F.Fab")
		)
		(fp_line
			(start 0.12065 -0.3048)
			(end 0.67945 -0.3048)
			(stroke
				(width 0.1)
				(type default)
			)
			(layer "F.Fab")
		)
		(fp_line
			(start 0.120396 0.3048)
			(end 0.120396 0.2794)
			(stroke
				(width 0.1)
				(type default)
			)
			(layer "F.Fab")
		)
		(fp_line
			(start 0.120396 0.2794)
			(end -0.12065 0.2794)
			(stroke
				(width 0.1)
				(type default)
			)
			(layer "F.Fab")
		)
		(fp_line
			(start -0.12065 0.3048)
			(end -0.67945 0.3048)
			(stroke
				(width 0.1)
				(type default)
			)
			(layer "F.Fab")
		)
		(fp_line
			(start -0.12065 0.2794)
			(end -0.12065 0.3048)
			(stroke
				(width 0.1)
				(type default)
			)
			(layer "F.Fab")
		)
		(fp_line
			(start -0.12065 -0.2794)
			(end 0.12065 -0.2794)
			(stroke
				(width 0.1)
				(type default)
			)
			(layer "F.Fab")
		)
		(fp_line
			(start -0.12065 -0.305054)
			(end -0.12065 -0.2794)
			(stroke
				(width 0.1)
				(type default)
			)
			(layer "F.Fab")
		)
		(fp_line
			(start -0.67945 0.3048)
			(end -0.67945 -0.305054)
			(stroke
				(width 0.1)
				(type default)
			)
			(layer "F.Fab")
		)
		(fp_line
			(start -0.67945 -0.305054)
			(end -0.12065 -0.305054)
			(stroke
				(width 0.1)
				(type default)
			)
			(layer "F.Fab")
		)
		(pad "1" smd circle
			(at -0.40005 0 180)
			(size 0 0)
			(layers "F.Cu" "F.Mask" "F.Paste")
			(net "HSC_SS")
		)
		(pad "2" smd circle
			(at 0.40005 0 180)
			(size 0 0)
			(layers "F.Cu" "F.Mask" "F.Paste")
			(net "AGND_HSC")
		)
	)
	(footprint ""
		(layer "F.Cu")
		(at 400.48307 -323.965316 180)
		(property "Reference" "R475"
			(at 0 0 180)
			(layer "F.SilkS")
			(hide yes)
			(effects
				(font
					(size 1.27 1.27)
				)
			)
		)
		(property "Value" ""
			(at 0 0 180)
			(layer "F.Fab")
			(effects
				(font
					(size 1.27 1.27)
				)
			)
		)
		(duplicate_pad_numbers_are_jumpers no)
		(fp_line
			(start 0.7874 0.4064)
			(end -0.7874 0.4064)
			(stroke
				(width 0.1524)
				(type default)
			)
			(layer "F.SilkS")
		)
		(fp_line
			(start 0.7874 -0.4064)
			(end 0.7874 0.4064)
			(stroke
				(width 0.1524)
				(type default)
			)
			(layer "F.SilkS")
		)
		(fp_line
			(start -0.7874 0.4064)
			(end -0.7874 -0.4064)
			(stroke
				(width 0.1524)
				(type default)
			)
			(layer "F.SilkS")
		)
		(fp_line
			(start -0.7874 -0.4064)
			(end 0.7874 -0.4064)
			(stroke
				(width 0.1524)
				(type default)
			)
			(layer "F.SilkS")
		)
		(fp_line
			(start 0.67945 0.3048)
			(end 0.120396 0.3048)
			(stroke
				(width 0.1)
				(type default)
			)
			(layer "F.Fab")
		)
		(fp_line
			(start 0.67945 -0.3048)
			(end 0.67945 0.3048)
			(stroke
				(width 0.1)
				(type default)
			)
			(layer "F.Fab")
		)
		(fp_line
			(start 0.12065 -0.2794)
			(end 0.12065 -0.3048)
			(stroke
				(width 0.1)
				(type default)
			)
			(layer "F.Fab")
		)
		(fp_line
			(start 0.12065 -0.3048)
			(end 0.67945 -0.3048)
			(stroke
				(width 0.1)
				(type default)
			)
			(layer "F.Fab")
		)
		(fp_line
			(start 0.120396 0.3048)
			(end 0.120396 0.2794)
			(stroke
				(width 0.1)
				(type default)
			)
			(layer "F.Fab")
		)
		(fp_line
			(start 0.120396 0.2794)
			(end -0.12065 0.2794)
			(stroke
				(width 0.1)
				(type default)
			)
			(layer "F.Fab")
		)
		(fp_line
			(start -0.12065 0.3048)
			(end -0.67945 0.3048)
			(stroke
				(width 0.1)
				(type default)
			)
			(layer "F.Fab")
		)
		(fp_line
			(start -0.12065 0.2794)
			(end -0.12065 0.3048)
			(stroke
				(width 0.1)
				(type default)
			)
			(layer "F.Fab")
		)
		(fp_line
			(start -0.12065 -0.2794)
			(end 0.12065 -0.2794)
			(stroke
				(width 0.1)
				(type default)
			)
			(layer "F.Fab")
		)
		(fp_line
			(start -0.12065 -0.305054)
			(end -0.12065 -0.2794)
			(stroke
				(width 0.1)
				(type default)
			)
			(layer "F.Fab")
		)
		(fp_line
			(start -0.67945 0.3048)
			(end -0.67945 -0.305054)
			(stroke
				(width 0.1)
				(type default)
			)
			(layer "F.Fab")
		)
		(fp_line
			(start -0.67945 -0.305054)
			(end -0.12065 -0.305054)
			(stroke
				(width 0.1)
				(type default)
			)
			(layer "F.Fab")
		)
		(pad "1" smd circle
			(at -0.40005 0 180)
			(size 0 0)
			(layers "F.Cu" "F.Mask" "F.Paste")
			(net "SPI_CPU0_TPM_CS_N")
		)
		(pad "2" smd circle
			(at 0.40005 0 180)
			(size 0 0)
			(layers "F.Cu" "F.Mask" "F.Paste")
			(net "SPI_CPU0_R_TPM_CS_N")
		)
	)
	(footprint ""
		(layer "F.Cu")
		(at 18.45564 -404.341584 90)
		(property "Reference" "R661"
			(at 0 0 90)
			(layer "F.SilkS")
			(hide yes)
			(effects
				(font
					(size 1.27 1.27)
				)
			)
		)
		(property "Value" ""
			(at 0 0 90)
			(layer "F.Fab")
			(effects
				(font
					(size 1.27 1.27)
				)
			)
		)
		(duplicate_pad_numbers_are_jumpers no)
		(fp_line
			(start 0.7874 -0.4064)
			(end 0.7874 0.4064)
			(stroke
				(width 0.1524)
				(type default)
			)
			(layer "F.SilkS")
		)
		(fp_line
			(start -0.7874 -0.4064)
			(end 0.7874 -0.4064)
			(stroke
				(width 0.1524)
				(type default)
			)
			(layer "F.SilkS")
		)
		(fp_line
			(start 0.7874 0.4064)
			(end -0.7874 0.4064)
			(stroke
				(width 0.1524)
				(type default)
			)
			(layer "F.SilkS")
		)
		(fp_line
			(start -0.7874 0.4064)
			(end -0.7874 -0.4064)
			(stroke
				(width 0.1524)
				(type default)
			)
			(layer "F.SilkS")
		)
		(fp_line
			(start -0.12065 -0.305054)
			(end -0.12065 -0.2794)
			(stroke
				(width 0.1)
				(type default)
			)
			(layer "F.Fab")
		)
		(fp_line
			(start -0.67945 -0.305054)
			(end -0.12065 -0.305054)
			(stroke
				(width 0.1)
				(type default)
			)
			(layer "F.Fab")
		)
		(fp_line
			(start 0.67945 -0.3048)
			(end 0.67945 0.3048)
			(stroke
				(width 0.1)
				(type default)
			)
			(layer "F.Fab")
		)
		(fp_line
			(start 0.12065 -0.3048)
			(end 0.67945 -0.3048)
			(stroke
				(width 0.1)
				(type default)
			)
			(layer "F.Fab")
		)
		(fp_line
			(start 0.12065 -0.2794)
			(end 0.12065 -0.3048)
			(stroke
				(width 0.1)
				(type default)
			)
			(layer "F.Fab")
		)
		(fp_line
			(start -0.12065 -0.2794)
			(end 0.12065 -0.2794)
			(stroke
				(width 0.1)
				(type default)
			)
			(layer "F.Fab")
		)
		(fp_line
			(start 0.120396 0.2794)
			(end -0.12065 0.2794)
			(stroke
				(width 0.1)
				(type default)
			)
			(layer "F.Fab")
		)
		(fp_line
			(start -0.12065 0.2794)
			(end -0.12065 0.3048)
			(stroke
				(width 0.1)
				(type default)
			)
			(layer "F.Fab")
		)
		(fp_line
			(start 0.67945 0.3048)
			(end 0.120396 0.3048)
			(stroke
				(width 0.1)
				(type default)
			)
			(layer "F.Fab")
		)
		(fp_line
			(start 0.120396 0.3048)
			(end 0.120396 0.2794)
			(stroke
				(width 0.1)
				(type default)
			)
			(layer "F.Fab")
		)
		(fp_line
			(start -0.12065 0.3048)
			(end -0.67945 0.3048)
			(stroke
				(width 0.1)
				(type default)
			)
			(layer "F.Fab")
		)
		(fp_line
			(start -0.67945 0.3048)
			(end -0.67945 -0.305054)
			(stroke
				(width 0.1)
				(type default)
			)
			(layer "F.Fab")
		)
		(pad "1" smd circle
			(at -0.40005 0 90)
			(size 0 0)
			(layers "F.Cu" "F.Mask" "F.Paste")
			(net "PWRGD_P0V9_RETIMER_CPU1")
		)
		(pad "2" smd circle
			(at 0.40005 0 90)
			(size 0 0)
			(layers "F.Cu" "F.Mask" "F.Paste")
			(net "PWRGD_P0V9_RETIMER_CPU1_R")
		)
	)
	(footprint ""
		(layer "F.Cu")
		(at 187.316872 -428.930562 90)
		(property "Reference" "R3441"
			(at 0 0 90)
			(layer "F.SilkS")
			(hide yes)
			(effects
				(font
					(size 1.27 1.27)
				)
			)
		)
		(property "Value" ""
			(at 0 0 90)
			(layer "F.Fab")
			(effects
				(font
					(size 1.27 1.27)
				)
			)
		)
		(duplicate_pad_numbers_are_jumpers no)
		(fp_line
			(start 0.7874 -0.4064)
			(end 0.7874 0.4064)
			(stroke
				(width 0.1524)
				(type default)
			)
			(layer "F.SilkS")
		)
		(fp_line
			(start -0.7874 -0.4064)
			(end 0.7874 -0.4064)
			(stroke
				(width 0.1524)
				(type default)
			)
			(layer "F.SilkS")
		)
		(fp_line
			(start 0.7874 0.4064)
			(end -0.7874 0.4064)
			(stroke
				(width 0.1524)
				(type default)
			)
			(layer "F.SilkS")
		)
		(fp_line
			(start -0.7874 0.4064)
			(end -0.7874 -0.4064)
			(stroke
				(width 0.1524)
				(type default)
			)
			(layer "F.SilkS")
		)
		(fp_line
			(start -0.12065 -0.305054)
			(end -0.12065 -0.2794)
			(stroke
				(width 0.1)
				(type default)
			)
			(layer "F.Fab")
		)
		(fp_line
			(start -0.67945 -0.305054)
			(end -0.12065 -0.305054)
			(stroke
				(width 0.1)
				(type default)
			)
			(layer "F.Fab")
		)
		(fp_line
			(start 0.67945 -0.3048)
			(end 0.67945 0.3048)
			(stroke
				(width 0.1)
				(type default)
			)
			(layer "F.Fab")
		)
		(fp_line
			(start 0.12065 -0.3048)
			(end 0.67945 -0.3048)
			(stroke
				(width 0.1)
				(type default)
			)
			(layer "F.Fab")
		)
		(fp_line
			(start 0.12065 -0.2794)
			(end 0.12065 -0.3048)
			(stroke
				(width 0.1)
				(type default)
			)
			(layer "F.Fab")
		)
		(fp_line
			(start -0.12065 -0.2794)
			(end 0.12065 -0.2794)
			(stroke
				(width 0.1)
				(type default)
			)
			(layer "F.Fab")
		)
		(fp_line
			(start 0.120396 0.2794)
			(end -0.12065 0.2794)
			(stroke
				(width 0.1)
				(type default)
			)
			(layer "F.Fab")
		)
		(fp_line
			(start -0.12065 0.2794)
			(end -0.12065 0.3048)
			(stroke
				(width 0.1)
				(type default)
			)
			(layer "F.Fab")
		)
		(fp_line
			(start 0.67945 0.3048)
			(end 0.120396 0.3048)
			(stroke
				(width 0.1)
				(type default)
			)
			(layer "F.Fab")
		)
		(fp_line
			(start 0.120396 0.3048)
			(end 0.120396 0.2794)
			(stroke
				(width 0.1)
				(type default)
			)
			(layer "F.Fab")
		)
		(fp_line
			(start -0.12065 0.3048)
			(end -0.67945 0.3048)
			(stroke
				(width 0.1)
				(type default)
			)
			(layer "F.Fab")
		)
		(fp_line
			(start -0.67945 0.3048)
			(end -0.67945 -0.305054)
			(stroke
				(width 0.1)
				(type default)
			)
			(layer "F.Fab")
		)
		(pad "1" smd circle
			(at -0.40005 0 90)
			(size 0 0)
			(layers "F.Cu" "F.Mask" "F.Paste")
			(net "GPU_BASE_ID1")
		)
		(pad "2" smd circle
			(at 0.40005 0 90)
			(size 0 0)
			(layers "F.Cu" "F.Mask" "F.Paste")
			(net "GND")
		)
	)
	(footprint ""
		(layer "F.Cu")
		(at 169.724324 -382.038606 -90)
		(property "Reference" "R1421"
			(at 0 0 270)
			(layer "F.SilkS")
			(hide yes)
			(effects
				(font
					(size 1.27 1.27)
				)
			)
		)
		(property "Value" ""
			(at 0 0 270)
			(layer "F.Fab")
			(effects
				(font
					(size 1.27 1.27)
				)
			)
		)
		(duplicate_pad_numbers_are_jumpers no)
		(fp_line
			(start -0.32512 0.175006)
			(end -0.32512 -0.175006)
			(stroke
				(width 0.1)
				(type default)
			)
			(layer "F.Fab")
		)
		(fp_line
			(start 0.32512 0.175006)
			(end -0.32512 0.175006)
			(stroke
				(width 0.1)
				(type default)
			)
			(layer "F.Fab")
		)
		(fp_line
			(start -0.32512 -0.175006)
			(end 0.32512 -0.175006)
			(stroke
				(width 0.1)
				(type default)
			)
			(layer "F.Fab")
		)
		(fp_line
			(start 0.32512 -0.175006)
			(end 0.32512 0.175006)
			(stroke
				(width 0.1)
				(type default)
			)
			(layer "F.Fab")
		)
		(pad "1" smd rect
			(at -0.2667 0 270)
			(size 0.3048 0.381)
			(layers "F.Cu" "F.Mask" "F.Paste")
			(net "CLKREQ_RT_CPU1_P2_N")
		)
		(pad "2" smd rect
			(at 0.2667 0 90)
			(size 0.3048 0.381)
			(layers "F.Cu" "F.Mask" "F.Paste")
			(net "GND")
		)
	)
)
